(kicad_pcb
	(version 20260206)
	(generator "pcbnew")
	(generator_version "10.0")
	(general
		(thickness 1.6)
		(legacy_teardrops no)
	)
	(paper "A4")
	(title_block
		(title "03242023_DA0F0TMBIJ0_F0T_Motherboard_J_brd_V01_OCP.brd")
		(comment 1 "Grand Teton / footprints 2338-2343 of 6105")
	)
	(layers
		(0 "F.Cu" signal "TOP")
		(4 "In1.Cu" signal "GND")
		(6 "In2.Cu" signal "IN1")
		(8 "In3.Cu" signal "GND1")
		(10 "In4.Cu" signal "IN2")
		(12 "In5.Cu" signal "GND2")
		(14 "In6.Cu" signal "IN3")
		(16 "In7.Cu" signal "GND3")
		(18 "In8.Cu" signal "VCC")
		(20 "In9.Cu" signal "VCC1")
		(22 "In10.Cu" signal "GND4")
		(24 "In11.Cu" signal "IN4")
		(26 "In12.Cu" signal "GND5")
		(28 "In13.Cu" signal "IN5")
		(30 "In14.Cu" signal "GND6")
		(32 "In15.Cu" signal "IN6")
		(34 "In16.Cu" signal "GND7")
		(2 "B.Cu" signal "BOTTOM")
		(9 "F.Adhes" user "F.Adhesive")
		(11 "B.Adhes" user "B.Adhesive")
		(13 "F.Paste" user "Package Geometry/Pastemask Top")
		(15 "B.Paste" user "Package Geometry/Pastemask Bottom")
		(5 "F.SilkS" user "Ref Des/Silkscreen Top")
		(7 "B.SilkS" user "Ref Des/Silkscreen Bottom")
		(1 "F.Mask" user "Board Geometry/Soldermask Top")
		(3 "B.Mask" user "Board Geometry/Soldermask Bottom")
		(17 "Dwgs.User" user "User.Drawings")
		(19 "Cmts.User" user "User.Comments")
		(21 "Eco1.User" user "User.Eco1")
		(23 "Eco2.User" user "User.Eco2")
		(25 "Edge.Cuts" user "Board Geometry/Outline")
		(27 "Margin" user)
		(31 "F.CrtYd" user "Package Geometry/Place Bound Top")
		(29 "B.CrtYd" user "Package Geometry/Place Bound Bottom")
		(35 "F.Fab" user "Ref Des/Assembly Top")
		(33 "B.Fab" user "Ref Des/Assembly Bottom")
	)
	(footprint ""
		(layer "F.Cu")
		(at 279.40762 -425.69638)
		(property "Reference" "C2393"
			(at 0 0 0)
			(layer "F.SilkS")
			(hide yes)
			(effects
				(font
					(size 1.27 1.27)
				)
			)
		)
		(property "Value" ""
			(at 0 0 0)
			(layer "F.Fab")
			(effects
				(font
					(size 1.27 1.27)
				)
			)
		)
		(duplicate_pad_numbers_are_jumpers no)
		(fp_line
			(start -0.7874 -0.4064)
			(end 0.7874 -0.4064)
			(stroke
				(width 0.1524)
				(type default)
			)
			(layer "F.SilkS")
		)
		(fp_line
			(start -0.7874 0.4064)
			(end -0.7874 -0.4064)
			(stroke
				(width 0.1524)
				(type default)
			)
			(layer "F.SilkS")
		)
		(fp_line
			(start 0.7874 -0.4064)
			(end 0.7874 0.4064)
			(stroke
				(width 0.1524)
				(type default)
			)
			(layer "F.SilkS")
		)
		(fp_line
			(start 0.7874 0.4064)
			(end -0.7874 0.4064)
			(stroke
				(width 0.1524)
				(type default)
			)
			(layer "F.SilkS")
		)
		(fp_line
			(start -0.67945 -0.305054)
			(end -0.12065 -0.305054)
			(stroke
				(width 0.1)
				(type default)
			)
			(layer "F.Fab")
		)
		(fp_line
			(start -0.67945 0.3048)
			(end -0.67945 -0.305054)
			(stroke
				(width 0.1)
				(type default)
			)
			(layer "F.Fab")
		)
		(fp_line
			(start -0.12065 -0.305054)
			(end -0.12065 -0.2794)
			(stroke
				(width 0.1)
				(type default)
			)
			(layer "F.Fab")
		)
		(fp_line
			(start -0.12065 -0.2794)
			(end 0.12065 -0.2794)
			(stroke
				(width 0.1)
				(type default)
			)
			(layer "F.Fab")
		)
		(fp_line
			(start -0.12065 0.2794)
			(end -0.12065 0.3048)
			(stroke
				(width 0.1)
				(type default)
			)
			(layer "F.Fab")
		)
		(fp_line
			(start -0.12065 0.3048)
			(end -0.67945 0.3048)
			(stroke
				(width 0.1)
				(type default)
			)
			(layer "F.Fab")
		)
		(fp_line
			(start 0.120396 0.2794)
			(end -0.12065 0.2794)
			(stroke
				(width 0.1)
				(type default)
			)
			(layer "F.Fab")
		)
		(fp_line
			(start 0.120396 0.3048)
			(end 0.120396 0.2794)
			(stroke
				(width 0.1)
				(type default)
			)
			(layer "F.Fab")
		)
		(fp_line
			(start 0.12065 -0.3048)
			(end 0.67945 -0.3048)
			(stroke
				(width 0.1)
				(type default)
			)
			(layer "F.Fab")
		)
		(fp_line
			(start 0.12065 -0.2794)
			(end 0.12065 -0.3048)
			(stroke
				(width 0.1)
				(type default)
			)
			(layer "F.Fab")
		)
		(fp_line
			(start 0.67945 -0.3048)
			(end 0.67945 0.3048)
			(stroke
				(width 0.1)
				(type default)
			)
			(layer "F.Fab")
		)
		(fp_line
			(start 0.67945 0.3048)
			(end 0.120396 0.3048)
			(stroke
				(width 0.1)
				(type default)
			)
			(layer "F.Fab")
		)
		(pad "1" smd circle
			(at -0.40005 0)
			(size 0 0)
			(layers "F.Cu" "F.Mask" "F.Paste")
			(net "U369_VDD")
		)
		(pad "2" smd circle
			(at 0.40005 0)
			(size 0 0)
			(layers "F.Cu" "F.Mask" "F.Paste")
			(net "GND")
		)
	)
	(footprint ""
		(layer "F.Cu")
		(at 446.675002 -77.829918 90)
		(property "Reference" "PR832"
			(at 0 0 90)
			(layer "F.SilkS")
			(hide yes)
			(effects
				(font
					(size 1.27 1.27)
				)
			)
		)
		(property "Value" ""
			(at 0 0 90)
			(layer "F.Fab")
			(effects
				(font
					(size 1.27 1.27)
				)
			)
		)
		(duplicate_pad_numbers_are_jumpers no)
		(fp_line
			(start 0.7874 -0.4064)
			(end 0.7874 0.4064)
			(stroke
				(width 0.1524)
				(type default)
			)
			(layer "F.SilkS")
		)
		(fp_line
			(start -0.7874 -0.4064)
			(end 0.7874 -0.4064)
			(stroke
				(width 0.1524)
				(type default)
			)
			(layer "F.SilkS")
		)
		(fp_line
			(start 0.7874 0.4064)
			(end -0.7874 0.4064)
			(stroke
				(width 0.1524)
				(type default)
			)
			(layer "F.SilkS")
		)
		(fp_line
			(start -0.7874 0.4064)
			(end -0.7874 -0.4064)
			(stroke
				(width 0.1524)
				(type default)
			)
			(layer "F.SilkS")
		)
		(fp_line
			(start -0.12065 -0.305054)
			(end -0.12065 -0.2794)
			(stroke
				(width 0.1)
				(type default)
			)
			(layer "F.Fab")
		)
		(fp_line
			(start -0.67945 -0.305054)
			(end -0.12065 -0.305054)
			(stroke
				(width 0.1)
				(type default)
			)
			(layer "F.Fab")
		)
		(fp_line
			(start 0.67945 -0.3048)
			(end 0.67945 0.3048)
			(stroke
				(width 0.1)
				(type default)
			)
			(layer "F.Fab")
		)
		(fp_line
			(start 0.12065 -0.3048)
			(end 0.67945 -0.3048)
			(stroke
				(width 0.1)
				(type default)
			)
			(layer "F.Fab")
		)
		(fp_line
			(start 0.12065 -0.2794)
			(end 0.12065 -0.3048)
			(stroke
				(width 0.1)
				(type default)
			)
			(layer "F.Fab")
		)
		(fp_line
			(start -0.12065 -0.2794)
			(end 0.12065 -0.2794)
			(stroke
				(width 0.1)
				(type default)
			)
			(layer "F.Fab")
		)
		(fp_line
			(start 0.120396 0.2794)
			(end -0.12065 0.2794)
			(stroke
				(width 0.1)
				(type default)
			)
			(layer "F.Fab")
		)
		(fp_line
			(start -0.12065 0.2794)
			(end -0.12065 0.3048)
			(stroke
				(width 0.1)
				(type default)
			)
			(layer "F.Fab")
		)
		(fp_line
			(start 0.67945 0.3048)
			(end 0.120396 0.3048)
			(stroke
				(width 0.1)
				(type default)
			)
			(layer "F.Fab")
		)
		(fp_line
			(start 0.120396 0.3048)
			(end 0.120396 0.2794)
			(stroke
				(width 0.1)
				(type default)
			)
			(layer "F.Fab")
		)
		(fp_line
			(start -0.12065 0.3048)
			(end -0.67945 0.3048)
			(stroke
				(width 0.1)
				(type default)
			)
			(layer "F.Fab")
		)
		(fp_line
			(start -0.67945 0.3048)
			(end -0.67945 -0.305054)
			(stroke
				(width 0.1)
				(type default)
			)
			(layer "F.Fab")
		)
		(pad "1" smd circle
			(at -0.40005 0 90)
			(size 0 0)
			(layers "F.Cu" "F.Mask" "F.Paste")
			(net "P3V3_AUX_MODE")
		)
		(pad "2" smd circle
			(at 0.40005 0 90)
			(size 0 0)
			(layers "F.Cu" "F.Mask" "F.Paste")
			(net "GND")
		)
	)
	(footprint ""
		(layer "F.Cu")
		(at 27.0383 -129.380996 180)
		(property "Reference" "PC467"
			(at 0 0 180)
			(layer "F.SilkS")
			(hide yes)
			(effects
				(font
					(size 1.27 1.27)
				)
			)
		)
		(property "Value" ""
			(at 0 0 180)
			(layer "F.Fab")
			(effects
				(font
					(size 1.27 1.27)
				)
			)
		)
		(duplicate_pad_numbers_are_jumpers no)
		(fp_line
			(start 0.7874 0.4064)
			(end -0.7874 0.4064)
			(stroke
				(width 0.1524)
				(type default)
			)
			(layer "F.SilkS")
		)
		(fp_line
			(start 0.7874 -0.4064)
			(end 0.7874 0.4064)
			(stroke
				(width 0.1524)
				(type default)
			)
			(layer "F.SilkS")
		)
		(fp_line
			(start -0.7874 0.4064)
			(end -0.7874 -0.4064)
			(stroke
				(width 0.1524)
				(type default)
			)
			(layer "F.SilkS")
		)
		(fp_line
			(start -0.7874 -0.4064)
			(end 0.7874 -0.4064)
			(stroke
				(width 0.1524)
				(type default)
			)
			(layer "F.SilkS")
		)
		(fp_line
			(start 0.67945 0.3048)
			(end 0.120396 0.3048)
			(stroke
				(width 0.1)
				(type default)
			)
			(layer "F.Fab")
		)
		(fp_line
			(start 0.67945 -0.3048)
			(end 0.67945 0.3048)
			(stroke
				(width 0.1)
				(type default)
			)
			(layer "F.Fab")
		)
		(fp_line
			(start 0.12065 -0.2794)
			(end 0.12065 -0.3048)
			(stroke
				(width 0.1)
				(type default)
			)
			(layer "F.Fab")
		)
		(fp_line
			(start 0.12065 -0.3048)
			(end 0.67945 -0.3048)
			(stroke
				(width 0.1)
				(type default)
			)
			(layer "F.Fab")
		)
		(fp_line
			(start 0.120396 0.3048)
			(end 0.120396 0.2794)
			(stroke
				(width 0.1)
				(type default)
			)
			(layer "F.Fab")
		)
		(fp_line
			(start 0.120396 0.2794)
			(end -0.12065 0.2794)
			(stroke
				(width 0.1)
				(type default)
			)
			(layer "F.Fab")
		)
		(fp_line
			(start -0.12065 0.3048)
			(end -0.67945 0.3048)
			(stroke
				(width 0.1)
				(type default)
			)
			(layer "F.Fab")
		)
		(fp_line
			(start -0.12065 0.2794)
			(end -0.12065 0.3048)
			(stroke
				(width 0.1)
				(type default)
			)
			(layer "F.Fab")
		)
		(fp_line
			(start -0.12065 -0.2794)
			(end 0.12065 -0.2794)
			(stroke
				(width 0.1)
				(type default)
			)
			(layer "F.Fab")
		)
		(fp_line
			(start -0.12065 -0.305054)
			(end -0.12065 -0.2794)
			(stroke
				(width 0.1)
				(type default)
			)
			(layer "F.Fab")
		)
		(fp_line
			(start -0.67945 0.3048)
			(end -0.67945 -0.305054)
			(stroke
				(width 0.1)
				(type default)
			)
			(layer "F.Fab")
		)
		(fp_line
			(start -0.67945 -0.305054)
			(end -0.12065 -0.305054)
			(stroke
				(width 0.1)
				(type default)
			)
			(layer "F.Fab")
		)
		(pad "1" smd circle
			(at -0.40005 0 180)
			(size 0 0)
			(layers "F.Cu" "F.Mask" "F.Paste")
			(net "PVCCINFAON_CPU1_CSPIN")
		)
		(pad "2" smd circle
			(at 0.40005 0 180)
			(size 0 0)
			(layers "F.Cu" "F.Mask" "F.Paste")
			(net "GND")
		)
	)
	(footprint ""
		(layer "F.Cu")
		(at 116.561616 -260.36524 -90)
		(property "Reference" "C439"
			(at 0 0 270)
			(layer "F.SilkS")
			(hide yes)
			(effects
				(font
					(size 1.27 1.27)
				)
			)
		)
		(property "Value" ""
			(at 0 0 270)
			(layer "F.Fab")
			(effects
				(font
					(size 1.27 1.27)
				)
			)
		)
		(duplicate_pad_numbers_are_jumpers no)
		(fp_line
			(start -0.7874 0.4064)
			(end -0.7874 -0.4064)
			(stroke
				(width 0.1524)
				(type default)
			)
			(layer "F.SilkS")
		)
		(fp_line
			(start 0.7874 0.4064)
			(end -0.7874 0.4064)
			(stroke
				(width 0.1524)
				(type default)
			)
			(layer "F.SilkS")
		)
		(fp_line
			(start -0.7874 -0.4064)
			(end 0.7874 -0.4064)
			(stroke
				(width 0.1524)
				(type default)
			)
			(layer "F.SilkS")
		)
		(fp_line
			(start 0.7874 -0.4064)
			(end 0.7874 0.4064)
			(stroke
				(width 0.1524)
				(type default)
			)
			(layer "F.SilkS")
		)
		(fp_line
			(start -0.67945 0.3048)
			(end -0.67945 -0.305054)
			(stroke
				(width 0.1)
				(type default)
			)
			(layer "F.Fab")
		)
		(fp_line
			(start -0.12065 0.3048)
			(end -0.67945 0.3048)
			(stroke
				(width 0.1)
				(type default)
			)
			(layer "F.Fab")
		)
		(fp_line
			(start 0.120396 0.3048)
			(end 0.120396 0.2794)
			(stroke
				(width 0.1)
				(type default)
			)
			(layer "F.Fab")
		)
		(fp_line
			(start 0.67945 0.3048)
			(end 0.120396 0.3048)
			(stroke
				(width 0.1)
				(type default)
			)
			(layer "F.Fab")
		)
		(fp_line
			(start -0.12065 0.2794)
			(end -0.12065 0.3048)
			(stroke
				(width 0.1)
				(type default)
			)
			(layer "F.Fab")
		)
		(fp_line
			(start 0.120396 0.2794)
			(end -0.12065 0.2794)
			(stroke
				(width 0.1)
				(type default)
			)
			(layer "F.Fab")
		)
		(fp_line
			(start -0.12065 -0.2794)
			(end 0.12065 -0.2794)
			(stroke
				(width 0.1)
				(type default)
			)
			(layer "F.Fab")
		)
		(fp_line
			(start 0.12065 -0.2794)
			(end 0.12065 -0.3048)
			(stroke
				(width 0.1)
				(type default)
			)
			(layer "F.Fab")
		)
		(fp_line
			(start 0.12065 -0.3048)
			(end 0.67945 -0.3048)
			(stroke
				(width 0.1)
				(type default)
			)
			(layer "F.Fab")
		)
		(fp_line
			(start 0.67945 -0.3048)
			(end 0.67945 0.3048)
			(stroke
				(width 0.1)
				(type default)
			)
			(layer "F.Fab")
		)
		(fp_line
			(start -0.67945 -0.305054)
			(end -0.12065 -0.305054)
			(stroke
				(width 0.1)
				(type default)
			)
			(layer "F.Fab")
		)
		(fp_line
			(start -0.12065 -0.305054)
			(end -0.12065 -0.2794)
			(stroke
				(width 0.1)
				(type default)
			)
			(layer "F.Fab")
		)
		(pad "1" smd circle
			(at -0.40005 0 270)
			(size 0 0)
			(layers "F.Cu" "F.Mask" "F.Paste")
			(net "PVCCFA_EHV_FIVRA_CPU1")
		)
		(pad "2" smd circle
			(at 0.40005 0 270)
			(size 0 0)
			(layers "F.Cu" "F.Mask" "F.Paste")
			(net "GND")
		)
	)
	(footprint ""
		(layer "F.Cu")
		(at 483.383844 -334.829912 180)
		(property "Reference" "DB9"
			(at -2.448052 0.158496 90)
			(unlocked yes)
			(layer "F.SilkS")
			(effects
				(font
					(size 0.7874 0.5842)
					(thickness 0.1524)
				)
				(justify left)
			)
		)
		(property "Value" ""
			(at 0 0 180)
			(layer "F.Fab")
			(effects
				(font
					(size 1.27 1.27)
				)
			)
		)
		(duplicate_pad_numbers_are_jumpers no)
		(fp_line
			(start 3.330702 -4.771136)
			(end 0 4.011168)
			(stroke
				(width 0.1524)
				(type default)
			)
			(layer "F.SilkS")
		)
		(fp_line
			(start 0 4.011168)
			(end -3.330702 -4.771136)
			(stroke
				(width 0.1524)
				(type default)
			)
			(layer "F.SilkS")
		)
		(fp_line
			(start -3.330702 -4.771136)
			(end 3.330702 -4.771136)
			(stroke
				(width 0.1524)
				(type default)
			)
			(layer "F.SilkS")
		)
		(fp_line
			(start 3.330702 -4.771136)
			(end 0 4.011168)
			(stroke
				(width 0.1)
				(type default)
			)
			(layer "F.Fab")
		)
		(fp_line
			(start 0 4.011168)
			(end -3.330702 -4.771136)
			(stroke
				(width 0.1)
				(type default)
			)
			(layer "F.Fab")
		)
		(fp_line
			(start -3.330702 -4.771136)
			(end 3.330702 -4.771136)
			(stroke
				(width 0.1)
				(type default)
			)
			(layer "F.Fab")
		)
		(pad "1" thru_hole circle
			(at 0 0 180)
			(size 2.159 2.159)
			(drill 1.7018)
			(layers "*.Cu" "*.Mask")
			(remove_unused_layers no)
			(net "T1_GND")
			(clearance 0.0254)
			(thermal_gap 0.0254)
		)
		(pad "2" thru_hole circle
			(at -1.27 -3.348736 180)
			(size 2.159 2.159)
			(drill 1.7018)
			(layers "*.Cu" "*.Mask")
			(remove_unused_layers no)
			(net "TDR_SE_50_OHM_IN2")
			(clearance 0.0254)
			(thermal_gap 0.0254)
		)
		(pad "3" thru_hole circle
			(at 1.27 -3.348736 180)
			(size 2.159 2.159)
			(drill 1.7018)
			(layers "*.Cu" "*.Mask")
			(remove_unused_layers no)
			(net "TDR_SE_50_OHM_IN2")
			(clearance 0.0254)
			(thermal_gap 0.0254)
		)
	)
	(footprint ""
		(layer "F.Cu")
		(at 133.65988 -103.723948 -90)
		(property "Reference" "Q140"
			(at -0.035052 -2.76479 90)
			(unlocked yes)
			(layer "F.SilkS")
			(effects
				(font
					(size 0.7874 0.5842)
					(thickness 0.1524)
				)
			)
		)
		(property "Value" ""
			(at 0 0 270)
			(layer "F.Fab")
			(effects
				(font
					(size 1.27 1.27)
				)
			)
		)
		(duplicate_pad_numbers_are_jumpers no)
		(fp_line
			(start -1.376172 1.199896)
			(end -1.376172 -1.199896)
			(stroke
				(width 0.1524)
				(type default)
			)
			(layer "F.SilkS")
		)
		(fp_line
			(start 1.376172 1.199896)
			(end -1.376172 1.199896)
			(stroke
				(width 0.1524)
				(type default)
			)
			(layer "F.SilkS")
		)
		(fp_line
			(start 0 -0.762)
			(end 0.508 -1.199896)
			(stroke
				(width 0.1524)
				(type default)
			)
			(layer "F.SilkS")
		)
		(fp_line
			(start -1.376172 -1.199896)
			(end -0.508 -1.199896)
			(stroke
				(width 0.1524)
				(type default)
			)
			(layer "F.SilkS")
		)
		(fp_line
			(start -0.508 -1.199896)
			(end 0 -0.762)
			(stroke
				(width 0.1524)
				(type default)
			)
			(layer "F.SilkS")
		)
		(fp_line
			(start 0.508 -1.199896)
			(end 1.376172 -1.199896)
			(stroke
				(width 0.1524)
				(type default)
			)
			(layer "F.SilkS")
		)
		(fp_line
			(start 1.376172 -1.199896)
			(end 1.376172 1.199896)
			(stroke
				(width 0.1524)
				(type default)
			)
			(layer "F.SilkS")
		)
		(fp_poly
			(pts
				(xy -0.880872 -1.369568) (xy -0.499872 -2.131568) (xy -1.261872 -2.131568)
			)
			(stroke
				(width 0)
				(type default)
			)
			(fill yes)
			(layer "F.SilkS")
		)
		(fp_line
			(start -0.674878 1.100074)
			(end -0.674878 -1.100074)
			(stroke
				(width 0.1)
				(type default)
			)
			(layer "F.Fab")
		)
		(fp_line
			(start 0.674878 1.100074)
			(end -0.674878 1.100074)
			(stroke
				(width 0.1)
				(type default)
			)
			(layer "F.Fab")
		)
		(fp_line
			(start -0.674878 -1.100074)
			(end 0.674878 -1.100074)
			(stroke
				(width 0.1)
				(type default)
			)
			(layer "F.Fab")
		)
		(fp_line
			(start 0.674878 -1.100074)
			(end 0.674878 1.100074)
			(stroke
				(width 0.1)
				(type default)
			)
			(layer "F.Fab")
		)
		(fp_poly
			(pts
				(xy -1.4605 -0.7493) (xy -2.2225 -1.1303) (xy -2.2225 -0.3683)
			)
			(stroke
				(width 0)
				(type default)
			)
			(fill yes)
			(layer "F.Fab")
		)
		(pad "1" smd rect
			(at -0.899922 -0.750062 180)
			(size 0.6096 0.6096)
			(layers "F.Cu" "F.Mask" "F.Paste")
			(net "GND")
		)
		(pad "2" smd rect
			(at -0.899922 0 180)
			(size 0.4064 0.6096)
			(layers "F.Cu" "F.Mask" "F.Paste")
			(net "H_CPU1_MEMTRIP_R")
		)
		(pad "3" smd rect
			(at -0.899922 0.750062 180)
			(size 0.6096 0.6096)
			(layers "F.Cu" "F.Mask" "F.Paste")
			(net "H_CPU1_MEMTRIP")
		)
		(pad "4" smd rect
			(at 0.899922 0.750062 180)
			(size 0.6096 0.6096)
			(layers "F.Cu" "F.Mask" "F.Paste")
			(net "PVNN_TERM_CPU1")
		)
		(pad "5" smd rect
			(at 0.899922 0 180)
			(size 0.4064 0.6096)
			(layers "F.Cu" "F.Mask" "F.Paste")
			(net "H_CPU1_MEMTRIP_OUT_VT_R_N")
		)
		(pad "6" smd rect
			(at 0.899922 -0.750062 180)
			(size 0.6096 0.6096)
			(layers "F.Cu" "F.Mask" "F.Paste")
			(net "H_CPU1_MEMTRIP_VT_N")
		)
	)
)
